# S9S_MB_2U (Grand Teton) — schematic netlist excerpt (pin names and nets, part order shuffled) for the footprints in the layout excerpt that follows; sources: Cadence DE-HDL packaged netlist, KiCad conversion of 03242023_DA0F0TMBIJ0_F0T_Motherboard_J_brd_V01_OCP.brd

PR2556  Q_RES  0.03 0.1% EMPTY  pkg 2512LF  page 285 : A = P12V_AUX ; B = SW_P12V_PVCCIN_CPU1_FLT
R122  Q_RES  0 5% CHIP  pkg 0402LF  page 125 : A = PWRGD_DRAMPWRGD_CPU1_AB_R_LVC1 ; B = PWRGD_DRAMPWRGD_CPU1_AB_LVC1_R2
R379  Q_RES  1K 1% CHIP  pkg 0402LF  page 198 : A = FM_ADR_MODE1 ; B = GND

(kicad_pcb
	(version 20260206)
	(generator "pcbnew")
	(generator_version "10.0")
	(general
		(thickness 1.6)
		(legacy_teardrops no)
	)
	(paper "A4")
	(title_block
		(title "03242023_DA0F0TMBIJ0_F0T_Motherboard_J_brd_V01_OCP.brd")
		(comment 1 "Grand Teton / footprints 5244-5246 of 6105")
	)
	(layers
		(0 "F.Cu" signal "TOP")
		(4 "In1.Cu" signal "GND")
		(6 "In2.Cu" signal "IN1")
		(8 "In3.Cu" signal "GND1")
		(10 "In4.Cu" signal "IN2")
		(12 "In5.Cu" signal "GND2")
		(14 "In6.Cu" signal "IN3")
		(16 "In7.Cu" signal "GND3")
		(18 "In8.Cu" signal "VCC")
		(20 "In9.Cu" signal "VCC1")
		(22 "In10.Cu" signal "GND4")
		(24 "In11.Cu" signal "IN4")
		(26 "In12.Cu" signal "GND5")
		(28 "In13.Cu" signal "IN5")
		(30 "In14.Cu" signal "GND6")
		(32 "In15.Cu" signal "IN6")
		(34 "In16.Cu" signal "GND7")
		(2 "B.Cu" signal "BOTTOM")
		(9 "F.Adhes" user "F.Adhesive")
		(11 "B.Adhes" user "B.Adhesive")
		(13 "F.Paste" user "Package Geometry/Pastemask Top")
		(15 "B.Paste" user "Package Geometry/Pastemask Bottom")
		(5 "F.SilkS" user "Ref Des/Silkscreen Top")
		(7 "B.SilkS" user "Ref Des/Silkscreen Bottom")
		(1 "F.Mask" user "Board Geometry/Soldermask Top")
		(3 "B.Mask" user "Board Geometry/Soldermask Bottom")
		(17 "Dwgs.User" user "User.Drawings")
		(19 "Cmts.User" user "User.Comments")
		(21 "Eco1.User" user "User.Eco1")
		(23 "Eco2.User" user "User.Eco2")
		(25 "Edge.Cuts" user "Board Geometry/Outline")
		(27 "Margin" user)
		(31 "F.CrtYd" user "Package Geometry/Place Bound Top")
		(29 "B.CrtYd" user "Package Geometry/Place Bound Bottom")
		(35 "F.Fab" user "Ref Des/Assembly Top")
		(33 "B.Fab" user "Ref Des/Assembly Bottom")
	)
	(footprint ""
		(layer "B.Cu")
		(at 307.363622 -30.724348)
		(property "Reference" "R379"
			(at 0 0 0)
			(layer "B.SilkS")
			(hide yes)
			(effects
				(font
					(size 1.27 1.27)
				)
				(justify mirror)
			)
		)
		(property "Value" ""
			(at 0 0 0)
			(layer "B.Fab")
			(effects
				(font
					(size 1.27 1.27)
				)
				(justify mirror)
			)
		)
		(duplicate_pad_numbers_are_jumpers no)
		(fp_line
			(start -0.7874 -0.4064)
			(end -0.7874 0.4064)
			(stroke
				(width 0.1524)
				(type default)
			)
			(layer "B.SilkS")
		)
		(fp_line
			(start -0.7874 0.4064)
			(end 0.7874 0.4064)
			(stroke
				(width 0.1524)
				(type default)
			)
			(layer "B.SilkS")
		)
		(fp_line
			(start 0.7874 -0.4064)
			(end -0.7874 -0.4064)
			(stroke
				(width 0.1524)
				(type default)
			)
			(layer "B.SilkS")
		)
		(fp_line
			(start 0.7874 0.4064)
			(end 0.7874 -0.4064)
			(stroke
				(width 0.1524)
				(type default)
			)
			(layer "B.SilkS")
		)
		(fp_line
			(start -0.67945 -0.3048)
			(end -0.67945 0.3048)
			(stroke
				(width 0.1)
				(type default)
			)
			(layer "B.Fab")
		)
		(fp_line
			(start -0.67945 0.3048)
			(end -0.120396 0.3048)
			(stroke
				(width 0.1)
				(type default)
			)
			(layer "B.Fab")
		)
		(fp_line
			(start -0.12065 -0.3048)
			(end -0.67945 -0.3048)
			(stroke
				(width 0.1)
				(type default)
			)
			(layer "B.Fab")
		)
		(fp_line
			(start -0.12065 -0.2794)
			(end -0.12065 -0.3048)
			(stroke
				(width 0.1)
				(type default)
			)
			(layer "B.Fab")
		)
		(fp_line
			(start -0.120396 0.2794)
			(end 0.12065 0.2794)
			(stroke
				(width 0.1)
				(type default)
			)
			(layer "B.Fab")
		)
		(fp_line
			(start -0.120396 0.3048)
			(end -0.120396 0.2794)
			(stroke
				(width 0.1)
				(type default)
			)
			(layer "B.Fab")
		)
		(fp_line
			(start 0.12065 -0.305054)
			(end 0.12065 -0.2794)
			(stroke
				(width 0.1)
				(type default)
			)
			(layer "B.Fab")
		)
		(fp_line
			(start 0.12065 -0.2794)
			(end -0.12065 -0.2794)
			(stroke
				(width 0.1)
				(type default)
			)
			(layer "B.Fab")
		)
		(fp_line
			(start 0.12065 0.2794)
			(end 0.12065 0.3048)
			(stroke
				(width 0.1)
				(type default)
			)
			(layer "B.Fab")
		)
		(fp_line
			(start 0.12065 0.3048)
			(end 0.67945 0.3048)
			(stroke
				(width 0.1)
				(type default)
			)
			(layer "B.Fab")
		)
		(fp_line
			(start 0.67945 -0.305054)
			(end 0.12065 -0.305054)
			(stroke
				(width 0.1)
				(type default)
			)
			(layer "B.Fab")
		)
		(fp_line
			(start 0.67945 0.3048)
			(end 0.67945 -0.305054)
			(stroke
				(width 0.1)
				(type default)
			)
			(layer "B.Fab")
		)
		(pad "1" smd circle
			(at 0.40005 0 180)
			(size 0 0)
			(layers "B.Cu" "B.Mask" "B.Paste")
			(net "FM_ADR_MODE1")
		)
		(pad "2" smd circle
			(at -0.40005 0 180)
			(size 0 0)
			(layers "B.Cu" "B.Mask" "B.Paste")
			(net "GND")
		)
	)
	(footprint ""
		(layer "B.Cu")
		(at 92.973398 -355.03231 90)
		(property "Reference" "PR2556"
			(at 0 0 90)
			(layer "B.SilkS")
			(hide yes)
			(effects
				(font
					(size 1.27 1.27)
				)
				(justify mirror)
			)
		)
		(property "Value" ""
			(at 0 0 90)
			(layer "B.Fab")
			(effects
				(font
					(size 1.27 1.27)
				)
				(justify mirror)
			)
		)
		(duplicate_pad_numbers_are_jumpers no)
		(fp_line
			(start 4.0386 -1.7526)
			(end -4.0386 -1.7526)
			(stroke
				(width 0.1524)
				(type default)
			)
			(layer "B.SilkS")
		)
		(fp_line
			(start -4.0386 -1.7526)
			(end -4.0386 1.7526)
			(stroke
				(width 0.1524)
				(type default)
			)
			(layer "B.SilkS")
		)
		(fp_line
			(start 4.0386 1.7526)
			(end 4.0386 -1.7526)
			(stroke
				(width 0.1524)
				(type default)
			)
			(layer "B.SilkS")
		)
		(fp_line
			(start -4.0386 1.7526)
			(end 4.0386 1.7526)
			(stroke
				(width 0.1524)
				(type default)
			)
			(layer "B.SilkS")
		)
		(fp_line
			(start 4.0386 -1.7526)
			(end -4.0386 -1.7526)
			(stroke
				(width 0.1)
				(type default)
			)
			(layer "B.Fab")
		)
		(fp_line
			(start -4.0386 -1.7526)
			(end -4.0386 1.7526)
			(stroke
				(width 0.1)
				(type default)
			)
			(layer "B.Fab")
		)
		(fp_line
			(start 4.0386 1.7526)
			(end 4.0386 -1.7526)
			(stroke
				(width 0.1)
				(type default)
			)
			(layer "B.Fab")
		)
		(fp_line
			(start -4.0386 1.7526)
			(end 4.0386 1.7526)
			(stroke
				(width 0.1)
				(type default)
			)
			(layer "B.Fab")
		)
		(pad "1" smd rect
			(at 3.1115 0 270)
			(size 1.524 3.2004)
			(layers "B.Cu" "B.Mask" "B.Paste")
			(net "P12V_AUX")
		)
		(pad "2" smd rect
			(at -3.1115 0 270)
			(size 1.524 3.2004)
			(layers "B.Cu" "B.Mask" "B.Paste")
			(net "SW_P12V_PVCCIN_CPU1_FLT")
		)
	)
	(footprint ""
		(layer "B.Cu")
		(at 156.580078 -102.661466)
		(property "Reference" "R122"
			(at 0 0 0)
			(layer "B.SilkS")
			(hide yes)
			(effects
				(font
					(size 1.27 1.27)
				)
				(justify mirror)
			)
		)
		(property "Value" ""
			(at 0 0 0)
			(layer "B.Fab")
			(effects
				(font
					(size 1.27 1.27)
				)
				(justify mirror)
			)
		)
		(duplicate_pad_numbers_are_jumpers no)
		(fp_line
			(start -0.7874 -0.4064)
			(end -0.7874 0.4064)
			(stroke
				(width 0.1524)
				(type default)
			)
			(layer "B.SilkS")
		)
		(fp_line
			(start -0.7874 0.4064)
			(end 0.7874 0.4064)
			(stroke
				(width 0.1524)
				(type default)
			)
			(layer "B.SilkS")
		)
		(fp_line
			(start 0.7874 -0.4064)
			(end -0.7874 -0.4064)
			(stroke
				(width 0.1524)
				(type default)
			)
			(layer "B.SilkS")
		)
		(fp_line
			(start 0.7874 0.4064)
			(end 0.7874 -0.4064)
			(stroke
				(width 0.1524)
				(type default)
			)
			(layer "B.SilkS")
		)
		(fp_line
			(start -0.67945 -0.3048)
			(end -0.67945 0.3048)
			(stroke
				(width 0.1)
				(type default)
			)
			(layer "B.Fab")
		)
		(fp_line
			(start -0.67945 0.3048)
			(end -0.120396 0.3048)
			(stroke
				(width 0.1)
				(type default)
			)
			(layer "B.Fab")
		)
		(fp_line
			(start -0.12065 -0.3048)
			(end -0.67945 -0.3048)
			(stroke
				(width 0.1)
				(type default)
			)
			(layer "B.Fab")
		)
		(fp_line
			(start -0.12065 -0.2794)
			(end -0.12065 -0.3048)
			(stroke
				(width 0.1)
				(type default)
			)
			(layer "B.Fab")
		)
		(fp_line
			(start -0.120396 0.2794)
			(end 0.12065 0.2794)
			(stroke
				(width 0.1)
				(type default)
			)
			(layer "B.Fab")
		)
		(fp_line
			(start -0.120396 0.3048)
			(end -0.120396 0.2794)
			(stroke
				(width 0.1)
				(type default)
			)
			(layer "B.Fab")
		)
		(fp_line
			(start 0.12065 -0.305054)
			(end 0.12065 -0.2794)
			(stroke
				(width 0.1)
				(type default)
			)
			(layer "B.Fab")
		)
		(fp_line
			(start 0.12065 -0.2794)
			(end -0.12065 -0.2794)
			(stroke
				(width 0.1)
				(type default)
			)
			(layer "B.Fab")
		)
		(fp_line
			(start 0.12065 0.2794)
			(end 0.12065 0.3048)
			(stroke
				(width 0.1)
				(type default)
			)
			(layer "B.Fab")
		)
		(fp_line
			(start 0.12065 0.3048)
			(end 0.67945 0.3048)
			(stroke
				(width 0.1)
				(type default)
			)
			(layer "B.Fab")
		)
		(fp_line
			(start 0.67945 -0.305054)
			(end 0.12065 -0.305054)
			(stroke
				(width 0.1)
				(type default)
			)
			(layer "B.Fab")
		)
		(fp_line
			(start 0.67945 0.3048)
			(end 0.67945 -0.305054)
			(stroke
				(width 0.1)
				(type default)
			)
			(layer "B.Fab")
		)
		(pad "1" smd circle
			(at 0.40005 0 180)
			(size 0 0)
			(layers "B.Cu" "B.Mask" "B.Paste")
			(net "PWRGD_DRAMPWRGD_CPU1_AB_R_LVC1")
		)
		(pad "2" smd circle
			(at -0.40005 0 180)
			(size 0 0)
			(layers "B.Cu" "B.Mask" "B.Paste")
			(net "PWRGD_DRAMPWRGD_CPU1_AB_LVC1_R2")
		)
	)
)
